(kicad_pcb
	(version 20260206)
	(generator "pcbnew")
	(generator_version "10.0")
	(general
		(thickness 1.6)
		(legacy_teardrops no)
	)
	(paper "A4")
	(title_block
		(title "03242023_DA0F0TMBIJ0_F0T_Motherboard_J_brd_V01_OCP.brd")
		(comment 1 "Grand Teton / footprint 1682 of 6105 (U1), pads 3025-3134 of 4677")
	)
	(layers
		(0 "F.Cu" signal "TOP")
		(4 "In1.Cu" signal "GND")
		(6 "In2.Cu" signal "IN1")
		(8 "In3.Cu" signal "GND1")
		(10 "In4.Cu" signal "IN2")
		(12 "In5.Cu" signal "GND2")
		(14 "In6.Cu" signal "IN3")
		(16 "In7.Cu" signal "GND3")
		(18 "In8.Cu" signal "VCC")
		(20 "In9.Cu" signal "VCC1")
		(22 "In10.Cu" signal "GND4")
		(24 "In11.Cu" signal "IN4")
		(26 "In12.Cu" signal "GND5")
		(28 "In13.Cu" signal "IN5")
		(30 "In14.Cu" signal "GND6")
		(32 "In15.Cu" signal "IN6")
		(34 "In16.Cu" signal "GND7")
		(2 "B.Cu" signal "BOTTOM")
		(9 "F.Adhes" user "F.Adhesive")
		(11 "B.Adhes" user "B.Adhesive")
		(13 "F.Paste" user "Package Geometry/Pastemask Top")
		(15 "B.Paste" user "Package Geometry/Pastemask Bottom")
		(5 "F.SilkS" user "Ref Des/Silkscreen Top")
		(7 "B.SilkS" user "Ref Des/Silkscreen Bottom")
		(1 "F.Mask" user "Board Geometry/Soldermask Top")
		(3 "B.Mask" user "Board Geometry/Soldermask Bottom")
		(17 "Dwgs.User" user "User.Drawings")
		(19 "Cmts.User" user "User.Comments")
		(21 "Eco1.User" user "User.Eco1")
		(23 "Eco2.User" user "User.Eco2")
		(25 "Edge.Cuts" user "Board Geometry/Outline")
		(27 "Margin" user)
		(31 "F.CrtYd" user "Package Geometry/Place Bound Top")
		(29 "B.CrtYd" user "Package Geometry/Place Bound Bottom")
		(35 "F.Fab" user "Ref Des/Assembly Top")
		(33 "B.Fab" user "Ref Des/Assembly Bottom")
	)
	(footprint ""
		(layer "F.Cu")
		(at 111.93018 -251.76988 90)
		(property "Reference" "U1"
			(at -74.913236 41.548812 0)
			(unlocked yes)
			(layer "F.SilkS")
			(effects
				(font
					(size 1.6002 1.1938)
					(thickness 0.1524)
				)
				(justify left)
			)
		)
		(property "Value" ""
			(at 0 0 90)
			(layer "F.Fab")
			(effects
				(font
					(size 1.27 1.27)
				)
			)
		)
		(duplicate_pad_numbers_are_jumpers no)
		(pad "DR9" smd circle
			(at -30.914086 17.096486 270)
			(size 0.4318 0.4318)
			(layers "F.Cu" "F.Mask" "F.Paste")
			(net "GND")
		)
		(pad "DR11" smd circle
			(at -29.2862 17.096486 270)
			(size 0.4318 0.4318)
			(layers "F.Cu" "F.Mask" "F.Paste")
			(net "P5E_CPU1_PE2_RX_DP<9>")
		)
		(pad "DR13" smd circle
			(at -27.658314 17.096486 270)
			(size 0.4318 0.4318)
			(layers "F.Cu" "F.Mask" "F.Paste")
			(net "GND")
		)
		(pad "DR15" smd circle
			(at -26.030682 17.096486 270)
			(size 0.4318 0.4318)
			(layers "F.Cu" "F.Mask" "F.Paste")
			(net "P5E_CPU1_PE2_TX_DP<9>")
		)
		(pad "DR17" smd circle
			(at -24.402796 17.096486 270)
			(size 0.4318 0.4318)
			(layers "F.Cu" "F.Mask" "F.Paste")
			(net "M_F_CPU1_SB_DQ<31>")
		)
		(pad "DR19" smd circle
			(at -22.77491 17.096486 270)
			(size 0.4318 0.4318)
			(layers "F.Cu" "F.Mask" "F.Paste")
			(net "GND")
		)
		(pad "DR21" smd circle
			(at -21.147278 17.096486 270)
			(size 0.4318 0.4318)
			(layers "F.Cu" "F.Mask" "F.Paste")
			(net "M_H_CPU1_SB_DQS_DN<7>")
		)
		(pad "DR23" smd circle
			(at -19.519392 17.096486 270)
			(size 0.4318 0.4318)
			(layers "F.Cu" "F.Mask" "F.Paste")
			(net "GND")
		)
		(pad "DR25" smd circle
			(at -17.89176 17.096486 270)
			(size 0.4318 0.4318)
			(layers "F.Cu" "F.Mask" "F.Paste")
			(net "GND")
		)
		(pad "DR27" smd circle
			(at -16.263874 17.096486 270)
			(size 0.4318 0.4318)
			(layers "F.Cu" "F.Mask" "F.Paste")
			(net "M_G_CPU1_SB_DQS_DP<6>")
		)
		(pad "DR29" smd circle
			(at -14.635988 17.096486 270)
			(size 0.4318 0.4318)
			(layers "F.Cu" "F.Mask" "F.Paste")
			(net "GND")
		)
		(pad "DR31" smd circle
			(at -13.008356 17.096486 270)
			(size 0.4318 0.4318)
			(layers "F.Cu" "F.Mask" "F.Paste")
			(net "GND")
		)
		(pad "DR33" smd circle
			(at -11.380724 17.096486 270)
			(size 0.4318 0.4318)
			(layers "F.Cu" "F.Mask" "F.Paste")
			(net "M_G_CPU1_SB_DQS_DN<5>")
		)
		(pad "DR35" smd circle
			(at -9.752838 17.096486 270)
			(size 0.4318 0.4318)
			(layers "F.Cu" "F.Mask" "F.Paste")
			(net "GND")
		)
		(pad "DR37" smd circle
			(at -8.124952 17.096486 270)
			(size 0.4318 0.4318)
			(layers "F.Cu" "F.Mask" "F.Paste")
			(net "GND")
		)
		(pad "DR39" smd circle
			(at -6.49732 17.096486 270)
			(size 0.4318 0.4318)
			(layers "F.Cu" "F.Mask" "F.Paste")
			(net "M_H_CPU1_SB_PAR")
		)
		(pad "DR41" smd circle
			(at -4.869434 17.096486 270)
			(size 0.4318 0.4318)
			(layers "F.Cu" "F.Mask" "F.Paste")
			(net "GND")
		)
		(pad "DR43" smd circle
			(at -3.241802 17.096486 270)
			(size 0.4318 0.4318)
			(layers "F.Cu" "F.Mask" "F.Paste")
			(net "GND")
		)
		(pad "DR45" smd circle
			(at -1.613916 17.096486 270)
			(size 0.4318 0.4318)
			(layers "F.Cu" "F.Mask" "F.Paste")
			(net "M_G_CPU1_CLK_DN<0>")
		)
		(pad "DR48" smd circle
			(at 2.427732 17.206468 270)
			(size 0.4318 0.4318)
			(layers "F.Cu" "F.Mask" "F.Paste")
			(net "GND")
		)
		(pad "DR50" smd circle
			(at 4.055618 17.206468 270)
			(size 0.4318 0.4318)
			(layers "F.Cu" "F.Mask" "F.Paste")
			(net "GND")
		)
		(pad "DR52" smd circle
			(at 5.68325 17.206468 270)
			(size 0.4318 0.4318)
			(layers "F.Cu" "F.Mask" "F.Paste")
			(net "M_G_CPU1_SA_CA<1>")
		)
		(pad "DR54" smd circle
			(at 7.311136 17.206468 270)
			(size 0.4318 0.4318)
			(layers "F.Cu" "F.Mask" "F.Paste")
			(net "GND")
		)
		(pad "DR56" smd circle
			(at 8.939022 17.206468 270)
			(size 0.4318 0.4318)
			(layers "F.Cu" "F.Mask" "F.Paste")
			(net "GND")
		)
		(pad "DR58" smd circle
			(at 10.566654 17.206468 270)
			(size 0.4318 0.4318)
			(layers "F.Cu" "F.Mask" "F.Paste")
			(net "M_G_CPU1_SA_DQS_DN<9>")
		)
		(pad "DR60" smd circle
			(at 12.19454 17.206468 270)
			(size 0.4318 0.4318)
			(layers "F.Cu" "F.Mask" "F.Paste")
			(net "GND")
		)
		(pad "DR62" smd circle
			(at 13.822426 17.206468 270)
			(size 0.4318 0.4318)
			(layers "F.Cu" "F.Mask" "F.Paste")
			(net "GND")
		)
		(pad "DR64" smd circle
			(at 15.450058 17.206468 270)
			(size 0.4318 0.4318)
			(layers "F.Cu" "F.Mask" "F.Paste")
			(net "M_G_CPU1_SA_DQS_DN<8>")
		)
		(pad "DR66" smd circle
			(at 17.07769 17.206468 270)
			(size 0.4318 0.4318)
			(layers "F.Cu" "F.Mask" "F.Paste")
			(net "GND")
		)
		(pad "DR68" smd circle
			(at 18.705576 17.206468 270)
			(size 0.4318 0.4318)
			(layers "F.Cu" "F.Mask" "F.Paste")
			(net "GND")
		)
		(pad "DR70" smd circle
			(at 20.333462 17.206468 270)
			(size 0.4318 0.4318)
			(layers "F.Cu" "F.Mask" "F.Paste")
			(net "M_G_CPU1_SA_DQS_DN<6>")
		)
		(pad "DR72" smd circle
			(at 21.961094 17.206468 270)
			(size 0.4318 0.4318)
			(layers "F.Cu" "F.Mask" "F.Paste")
			(net "GND")
		)
		(pad "DR74" smd circle
			(at 23.58898 17.206468 270)
			(size 0.4318 0.4318)
			(layers "F.Cu" "F.Mask" "F.Paste")
			(net "GND")
		)
		(pad "DR76" smd circle
			(at 25.216612 17.206468 270)
			(size 0.4318 0.4318)
			(layers "F.Cu" "F.Mask" "F.Paste")
			(net "M_H_CPU1_SA_DQS_DN<5>")
		)
		(pad "DR78" smd circle
			(at 26.844498 17.206468 270)
			(size 0.4318 0.4318)
			(layers "F.Cu" "F.Mask" "F.Paste")
			(net "GND")
		)
		(pad "DR80" smd circle
			(at 28.472384 17.206468 270)
			(size 0.4318 0.4318)
			(layers "F.Cu" "F.Mask" "F.Paste")
			(net "Net_703")
		)
		(pad "DR82" smd circle
			(at 30.100016 17.206468 270)
			(size 0.4318 0.4318)
			(layers "F.Cu" "F.Mask" "F.Paste")
			(net "Net_728")
		)
		(pad "DR84" smd circle
			(at 31.727902 17.206468 270)
			(size 0.4318 0.4318)
			(layers "F.Cu" "F.Mask" "F.Paste")
			(net "GND")
		)
		(pad "DR86" smd circle
			(at 33.355534 17.206468 270)
			(size 0.4318 0.4318)
			(layers "F.Cu" "F.Mask" "F.Paste")
			(net "P5E_CPU1_PE3_TX_DP<5>")
		)
		(pad "DR88" smd circle
			(at 34.98342 17.206468 270)
			(size 0.4318 0.4318)
			(layers "F.Cu" "F.Mask" "F.Paste")
			(net "GND")
		)
		(pad "DR90" smd circle
			(at 36.611306 17.206468 270)
			(size 0.4318 0.4318)
			(layers "F.Cu" "F.Mask" "F.Paste")
			(net "P5E_CPU1_PE3_RX_DP<6>")
		)
		(pad "DT2" smd circle
			(at -36.611306 17.566132 270)
			(size 0.4318 0.4318)
			(layers "F.Cu" "F.Mask" "F.Paste")
			(net "UPI_CPU0_CPU1_P0P1_DN<6>")
		)
		(pad "DT4" smd circle
			(at -34.98342 17.566132 270)
			(size 0.4318 0.4318)
			(layers "F.Cu" "F.Mask" "F.Paste")
			(net "GND")
		)
		(pad "DT6" smd circle
			(at -33.355534 17.566132 270)
			(size 0.4318 0.4318)
			(layers "F.Cu" "F.Mask" "F.Paste")
			(net "UPI_CPU1_CPU0_P1P0_DN<5>")
		)
		(pad "DT8" smd circle
			(at -31.727902 17.566132 270)
			(size 0.4318 0.4318)
			(layers "F.Cu" "F.Mask" "F.Paste")
			(net "GND")
		)
		(pad "DT10" smd circle
			(at -30.100016 17.566132 270)
			(size 0.4318 0.4318)
			(layers "F.Cu" "F.Mask" "F.Paste")
			(net "P5E_CPU1_PE2_RX_DN<9>")
		)
		(pad "DT12" smd circle
			(at -28.472384 17.566132 270)
			(size 0.4318 0.4318)
			(layers "F.Cu" "F.Mask" "F.Paste")
			(net "GND")
		)
		(pad "DT14" smd circle
			(at -26.844498 17.566132 270)
			(size 0.4318 0.4318)
			(layers "F.Cu" "F.Mask" "F.Paste")
			(net "P5E_CPU1_PE2_TX_DP<10>")
		)
		(pad "DT16" smd circle
			(at -25.216612 17.566132 270)
			(size 0.4318 0.4318)
			(layers "F.Cu" "F.Mask" "F.Paste")
			(net "GND")
		)
		(pad "DT18" smd circle
			(at -23.58898 17.566132 270)
			(size 0.4318 0.4318)
			(layers "F.Cu" "F.Mask" "F.Paste")
			(net "M_F_CPU1_SB_DQS_DN<3>")
		)
		(pad "DT20" smd circle
			(at -21.961094 17.566132 270)
			(size 0.4318 0.4318)
			(layers "F.Cu" "F.Mask" "F.Paste")
			(net "GND")
		)
		(pad "DT22" smd circle
			(at -20.333462 17.566132 270)
			(size 0.4318 0.4318)
			(layers "F.Cu" "F.Mask" "F.Paste")
			(net "GND")
		)
		(pad "DT24" smd circle
			(at -18.705576 17.566132 270)
			(size 0.4318 0.4318)
			(layers "F.Cu" "F.Mask" "F.Paste")
			(net "M_G_CPU1_SB_DQS_DP<2>")
		)
		(pad "DT26" smd circle
			(at -17.07769 17.566132 270)
			(size 0.4318 0.4318)
			(layers "F.Cu" "F.Mask" "F.Paste")
			(net "GND")
		)
		(pad "DT28" smd circle
			(at -15.450058 17.566132 270)
			(size 0.4318 0.4318)
			(layers "F.Cu" "F.Mask" "F.Paste")
			(net "GND")
		)
		(pad "DT30" smd circle
			(at -13.822426 17.566132 270)
			(size 0.4318 0.4318)
			(layers "F.Cu" "F.Mask" "F.Paste")
			(net "M_F_CPU1_SB_DQS_DP<0>")
		)
		(pad "DT32" smd circle
			(at -12.19454 17.566132 270)
			(size 0.4318 0.4318)
			(layers "F.Cu" "F.Mask" "F.Paste")
			(net "GND")
		)
		(pad "DT34" smd circle
			(at -10.566654 17.566132 270)
			(size 0.4318 0.4318)
			(layers "F.Cu" "F.Mask" "F.Paste")
			(net "GND")
		)
		(pad "DT36" smd circle
			(at -8.939022 17.566132 270)
			(size 0.4318 0.4318)
			(layers "F.Cu" "F.Mask" "F.Paste")
			(net "M_G_CPU1_SB_DQS_DP<9>")
		)
		(pad "DT38" smd circle
			(at -7.311136 17.566132 270)
			(size 0.4318 0.4318)
			(layers "F.Cu" "F.Mask" "F.Paste")
			(net "GND")
		)
		(pad "DT40" smd circle
			(at -5.68325 17.566132 270)
			(size 0.4318 0.4318)
			(layers "F.Cu" "F.Mask" "F.Paste")
			(net "GND")
		)
		(pad "DT42" smd circle
			(at -4.055618 17.566132 270)
			(size 0.4318 0.4318)
			(layers "F.Cu" "F.Mask" "F.Paste")
			(net "M_G_CPU1_SB_CA<6>")
		)
		(pad "DT44" smd circle
			(at -2.427732 17.566132 270)
			(size 0.4318 0.4318)
			(layers "F.Cu" "F.Mask" "F.Paste")
			(net "GND")
		)
		(pad "DT47" smd circle
			(at 1.613916 17.676114 270)
			(size 0.4318 0.4318)
			(layers "F.Cu" "F.Mask" "F.Paste")
			(net "GND")
		)
		(pad "DT49" smd circle
			(at 3.241802 17.676114 270)
			(size 0.4318 0.4318)
			(layers "F.Cu" "F.Mask" "F.Paste")
			(net "M_F_CPU1_CLK_DP<1>")
		)
		(pad "DT51" smd circle
			(at 4.869434 17.676114 270)
			(size 0.4318 0.4318)
			(layers "F.Cu" "F.Mask" "F.Paste")
			(net "GND")
		)
		(pad "DT53" smd circle
			(at 6.49732 17.676114 270)
			(size 0.4318 0.4318)
			(layers "F.Cu" "F.Mask" "F.Paste")
			(net "GND")
		)
		(pad "DT55" smd circle
			(at 8.124952 17.676114 270)
			(size 0.4318 0.4318)
			(layers "F.Cu" "F.Mask" "F.Paste")
			(net "M_F_CPU1_SA_DQS_DP<3>")
		)
		(pad "DT57" smd circle
			(at 9.752838 17.676114 270)
			(size 0.4318 0.4318)
			(layers "F.Cu" "F.Mask" "F.Paste")
			(net "GND")
		)
		(pad "DT59" smd circle
			(at 11.380724 17.676114 270)
			(size 0.4318 0.4318)
			(layers "F.Cu" "F.Mask" "F.Paste")
			(net "GND")
		)
		(pad "DT61" smd circle
			(at 13.008356 17.676114 270)
			(size 0.4318 0.4318)
			(layers "F.Cu" "F.Mask" "F.Paste")
			(net "M_G_CPU1_SA_DQS_DN<2>")
		)
		(pad "DT63" smd circle
			(at 14.635988 17.676114 270)
			(size 0.4318 0.4318)
			(layers "F.Cu" "F.Mask" "F.Paste")
			(net "GND")
		)
		(pad "DT65" smd circle
			(at 16.263874 17.676114 270)
			(size 0.4318 0.4318)
			(layers "F.Cu" "F.Mask" "F.Paste")
			(net "GND")
		)
		(pad "DT67" smd circle
			(at 17.89176 17.676114 270)
			(size 0.4318 0.4318)
			(layers "F.Cu" "F.Mask" "F.Paste")
			(net "M_F_CPU1_SA_DQS_DN<1>")
		)
		(pad "DT69" smd circle
			(at 19.519392 17.676114 270)
			(size 0.4318 0.4318)
			(layers "F.Cu" "F.Mask" "F.Paste")
			(net "GND")
		)
		(pad "DT71" smd circle
			(at 21.147278 17.676114 270)
			(size 0.4318 0.4318)
			(layers "F.Cu" "F.Mask" "F.Paste")
			(net "GND")
		)
		(pad "DT73" smd circle
			(at 22.77491 17.676114 270)
			(size 0.4318 0.4318)
			(layers "F.Cu" "F.Mask" "F.Paste")
			(net "M_G_CPU1_SA_DQS_DP<0>")
		)
		(pad "DT75" smd circle
			(at 24.402796 17.676114 270)
			(size 0.4318 0.4318)
			(layers "F.Cu" "F.Mask" "F.Paste")
			(net "GND")
		)
		(pad "DT77" smd circle
			(at 26.030682 17.676114 270)
			(size 0.4318 0.4318)
			(layers "F.Cu" "F.Mask" "F.Paste")
			(net "M_H_CPU1_SA_DQ<1>")
		)
		(pad "DT79" smd circle
			(at 27.658314 17.676114 270)
			(size 0.4318 0.4318)
			(layers "F.Cu" "F.Mask" "F.Paste")
			(net "PVCCFA_EHV_FIVRA_CPU1")
		)
		(pad "DT81" smd circle
			(at 29.2862 17.676114 270)
			(size 0.4318 0.4318)
			(layers "F.Cu" "F.Mask" "F.Paste")
			(net "Net_705")
		)
		(pad "DT83" smd circle
			(at 30.914086 17.676114 270)
			(size 0.4318 0.4318)
			(layers "F.Cu" "F.Mask" "F.Paste")
			(net "GND")
		)
		(pad "DT85" smd circle
			(at 32.541718 17.676114 270)
			(size 0.4318 0.4318)
			(layers "F.Cu" "F.Mask" "F.Paste")
			(net "PVCCFA_EHV_FIVRA_CPU1")
		)
		(pad "DT87" smd circle
			(at 34.169604 17.676114 270)
			(size 0.4318 0.4318)
			(layers "F.Cu" "F.Mask" "F.Paste")
			(net "P5E_CPU1_PE3_TX_DN<4>")
		)
		(pad "DT89" smd circle
			(at 35.797236 17.676114 270)
			(size 0.4318 0.4318)
			(layers "F.Cu" "F.Mask" "F.Paste")
			(net "PVCCFA_EHV_FIVRA_CPU1")
		)
		(pad "DT91" smd oval
			(at 37.425122 17.676114)
			(size 0.381 0.4826)
			(drill
				(offset 0 -0.0508)
			)
			(layers "F.Cu" "F.Mask" "F.Paste")
			(net "P5E_CPU1_PE3_RX_DP<5>")
		)
		(pad "DU1" smd oval
			(at -37.425122 18.036286 180)
			(size 0.381 0.4826)
			(drill
				(offset 0 -0.0508)
			)
			(layers "F.Cu" "F.Mask" "F.Paste")
			(net "UPI_CPU0_CPU1_P0P1_DN<5>")
		)
		(pad "DU3" smd circle
			(at -35.797236 18.036286 270)
			(size 0.4318 0.4318)
			(layers "F.Cu" "F.Mask" "F.Paste")
			(net "PVCCFA_EHV_FIVRA_CPU1")
		)
		(pad "DU5" smd circle
			(at -34.169604 18.036286 270)
			(size 0.4318 0.4318)
			(layers "F.Cu" "F.Mask" "F.Paste")
			(net "UPI_CPU1_CPU0_P1P0_DP<4>")
		)
		(pad "DU7" smd circle
			(at -32.541718 18.036286 270)
			(size 0.4318 0.4318)
			(layers "F.Cu" "F.Mask" "F.Paste")
			(net "PVCCFA_EHV_FIVRA_CPU1")
		)
		(pad "DU9" smd circle
			(at -30.914086 18.036286 270)
			(size 0.4318 0.4318)
			(layers "F.Cu" "F.Mask" "F.Paste")
			(net "P5E_CPU1_PE2_RX_DN<10>")
		)
		(pad "DU11" smd circle
			(at -29.2862 18.036286 270)
			(size 0.4318 0.4318)
			(layers "F.Cu" "F.Mask" "F.Paste")
			(net "PVCCFA_EHV_FIVRA_CPU1")
		)
		(pad "DU13" smd circle
			(at -27.658314 18.036286 270)
			(size 0.4318 0.4318)
			(layers "F.Cu" "F.Mask" "F.Paste")
			(net "P5E_CPU1_PE2_TX_DN<10>")
		)
		(pad "DU15" smd circle
			(at -26.030682 18.036286 270)
			(size 0.4318 0.4318)
			(layers "F.Cu" "F.Mask" "F.Paste")
			(net "PVCCFA_EHV_FIVRA_CPU1")
		)
		(pad "DU17" smd circle
			(at -24.402796 18.036286 270)
			(size 0.4318 0.4318)
			(layers "F.Cu" "F.Mask" "F.Paste")
			(net "M_F_CPU1_SB_DQ<29>")
		)
		(pad "DU19" smd circle
			(at -22.77491 18.036286 270)
			(size 0.4318 0.4318)
			(layers "F.Cu" "F.Mask" "F.Paste")
			(net "M_F_CPU1_SB_DQ<25>")
		)
		(pad "DU21" smd circle
			(at -21.147278 18.036286 270)
			(size 0.4318 0.4318)
			(layers "F.Cu" "F.Mask" "F.Paste")
			(net "GND")
		)
		(pad "DU23" smd circle
			(at -19.519392 18.036286 270)
			(size 0.4318 0.4318)
			(layers "F.Cu" "F.Mask" "F.Paste")
			(net "M_G_CPU1_SB_DQ<20>")
		)
		(pad "DU25" smd circle
			(at -17.89176 18.036286 270)
			(size 0.4318 0.4318)
			(layers "F.Cu" "F.Mask" "F.Paste")
			(net "M_G_CPU1_SB_DQ<17>")
		)
		(pad "DU27" smd circle
			(at -16.263874 18.036286 270)
			(size 0.4318 0.4318)
			(layers "F.Cu" "F.Mask" "F.Paste")
			(net "GND")
		)
		(pad "DU29" smd circle
			(at -14.635988 18.036286 270)
			(size 0.4318 0.4318)
			(layers "F.Cu" "F.Mask" "F.Paste")
			(net "M_F_CPU1_SB_DQ<4>")
		)
		(pad "DU31" smd circle
			(at -13.008356 18.036286 270)
			(size 0.4318 0.4318)
			(layers "F.Cu" "F.Mask" "F.Paste")
			(net "M_F_CPU1_SB_DQ<1>")
		)
		(pad "DU33" smd circle
			(at -11.380724 18.036286 270)
			(size 0.4318 0.4318)
			(layers "F.Cu" "F.Mask" "F.Paste")
			(net "GND")
		)
		(pad "DU35" smd circle
			(at -9.752838 18.036286 270)
			(size 0.4318 0.4318)
			(layers "F.Cu" "F.Mask" "F.Paste")
			(net "M_G_CPU1_SB_CB<0>")
		)
		(pad "DU37" smd circle
			(at -8.124952 18.036286 270)
			(size 0.4318 0.4318)
			(layers "F.Cu" "F.Mask" "F.Paste")
			(net "M_G_CPU1_SB_CB<5>")
		)
		(pad "DU39" smd circle
			(at -6.49732 18.036286 270)
			(size 0.4318 0.4318)
			(layers "F.Cu" "F.Mask" "F.Paste")
			(net "GND")
		)
		(pad "DU41" smd circle
			(at -4.869434 18.036286 270)
			(size 0.4318 0.4318)
			(layers "F.Cu" "F.Mask" "F.Paste")
			(net "M_G_CPU1_SB_CS_N<2>")
		)
		(pad "DU43" smd circle
			(at -3.241802 18.036286 270)
			(size 0.4318 0.4318)
			(layers "F.Cu" "F.Mask" "F.Paste")
			(net "M_G_CPU1_SB_CA<4>")
		)
		(pad "DU45" smd circle
			(at -1.613916 18.036286 270)
			(size 0.4318 0.4318)
			(layers "F.Cu" "F.Mask" "F.Paste")
			(net "GND")
		)
		(pad "DU48" smd circle
			(at 2.427732 18.146268 270)
			(size 0.4318 0.4318)
			(layers "F.Cu" "F.Mask" "F.Paste")
			(net "M_G_CPU1_SB_RSP<0>")
		)
	)
)
